(kicad_pcb
	(version 20260206)
	(generator "pcbnew")
	(generator_version "10.0")
	(general
		(thickness 1.6)
		(legacy_teardrops no)
	)
	(paper "A4")
	(title_block
		(title "Bryce Canyon_IOM_IOC_16318-2_OCP.brd")
		(comment 1 "Bryce Canyon / footprints 1420-1426 of 1605")
	)
	(layers
		(0 "F.Cu" signal "TOP")
		(4 "In1.Cu" signal "L2GND")
		(6 "In2.Cu" signal "L3")
		(8 "In3.Cu" signal "L4VCC")
		(10 "In4.Cu" signal "L5VCC")
		(12 "In5.Cu" signal "L6")
		(14 "In6.Cu" signal "L7GND")
		(2 "B.Cu" signal "BOTTOM")
		(9 "F.Adhes" user "F.Adhesive")
		(11 "B.Adhes" user "B.Adhesive")
		(13 "F.Paste" user "Package Geometry/Pastemask Top")
		(15 "B.Paste" user "Package Geometry/Pastemask Bottom")
		(5 "F.SilkS" user "Ref Des/Silkscreen Top")
		(7 "B.SilkS" user "Ref Des/Silkscreen Bottom")
		(1 "F.Mask" user "Board Geometry/Soldermask Top")
		(3 "B.Mask" user "Board Geometry/Soldermask Bottom")
		(17 "Dwgs.User" user "User.Drawings")
		(19 "Cmts.User" user "User.Comments")
		(21 "Eco1.User" user "User.Eco1")
		(23 "Eco2.User" user "User.Eco2")
		(25 "Edge.Cuts" user "Board Geometry/Outline")
		(27 "Margin" user)
		(31 "F.CrtYd" user "Package Geometry/Place Bound Top")
		(29 "B.CrtYd" user "Package Geometry/Place Bound Bottom")
		(35 "F.Fab" user "Ref Des/Assembly Top")
		(33 "B.Fab" user "Ref Des/Assembly Bottom")
	)
	(footprint ""
		(layer "B.Cu")
		(at 89.3826 -134.7724 180)
		(property "Reference" "R688"
			(at 0 0 0)
			(layer "B.SilkS")
			(hide yes)
			(effects
				(font
					(size 1.27 1.27)
				)
				(justify mirror)
			)
		)
		(property "Value" "100KR2F-L1-GP"
			(at -0.064008 -3.993896 180)
			(unlocked yes)
			(layer "B.Fab")
			(hide yes)
			(effects
				(font
					(size 1.016 1.016)
					(thickness 0.1524)
				)
				(justify mirror)
			)
		)
		(property "Device Type" "R402H16"
			(at -0.064008 -5.517896 180)
			(unlocked yes)
			(layer "B.Fab")
			(hide yes)
			(effects
				(font
					(size 1.016 1.016)
					(thickness 0.1524)
				)
				(justify mirror)
			)
		)
		(duplicate_pad_numbers_are_jumpers no)
		(fp_line
			(start 0.508 -0.9398)
			(end 0.508 0.9398)
			(stroke
				(width 0.1524)
				(type default)
			)
			(layer "B.SilkS")
		)
		(fp_line
			(start -0.508 -0.9398)
			(end 0.508 -0.9398)
			(stroke
				(width 0.1524)
				(type default)
			)
			(layer "B.SilkS")
		)
		(fp_rect
			(start 0.508 0.9398)
			(end -0.508 -0.9398)
			(stroke
				(width 0)
				(type default)
			)
			(fill no)
			(layer "B.CrtYd")
		)
		(fp_rect
			(start 0.508 0.9398)
			(end -0.508 -0.9398)
			(stroke
				(width 0)
				(type default)
			)
			(fill no)
			(layer "B.Fab")
		)
		(pad "1" smd custom
			(at 0 -0.4445)
			(size 0.1397 0.1397)
			(layers "B.Cu" "B.Mask" "B.Paste")
			(net "P3V3_STBY")
			(options
				(clearance outline)
				(anchor circle)
			)
			(primitives
				(gr_poly
					(pts
						(arc
							(start -0.1778 0.2794)
							(mid -0.249642 0.249642)
							(end -0.2794 0.1778)
						)
						(arc
							(start -0.2794 -0.1778)
							(mid -0.249642 -0.249642)
							(end -0.1778 -0.2794)
						)
						(arc
							(start 0.1778 -0.2794)
							(mid 0.249642 -0.249642)
							(end 0.2794 -0.1778)
						)
						(arc
							(start 0.2794 0.1778)
							(mid 0.249642 0.249642)
							(end 0.1778 0.2794)
						)
					)
					(width 0)
					(fill yes)
				)
			)
		)
		(pad "2" smd custom
			(at 0 0.4445)
			(size 0.1397 0.1397)
			(layers "B.Cu" "B.Mask" "B.Paste")
			(net "DEBUG_UART_IOM_RX")
			(options
				(clearance outline)
				(anchor circle)
			)
			(primitives
				(gr_poly
					(pts
						(arc
							(start -0.1778 0.2794)
							(mid -0.249642 0.249642)
							(end -0.2794 0.1778)
						)
						(arc
							(start -0.2794 -0.1778)
							(mid -0.249642 -0.249642)
							(end -0.1778 -0.2794)
						)
						(arc
							(start 0.1778 -0.2794)
							(mid 0.249642 -0.249642)
							(end 0.2794 -0.1778)
						)
						(arc
							(start 0.2794 0.1778)
							(mid 0.249642 0.249642)
							(end 0.1778 0.2794)
						)
					)
					(width 0)
					(fill yes)
				)
			)
		)
	)
	(footprint ""
		(layer "B.Cu")
		(at 53.19903 -132.651246 180)
		(property "Reference" "C115"
			(at 0 0 0)
			(layer "B.SilkS")
			(hide yes)
			(effects
				(font
					(size 1.27 1.27)
				)
				(justify mirror)
			)
		)
		(property "Value" "SC10U6D3V3KX-1-GP"
			(at 0 -2.8194 180)
			(unlocked yes)
			(layer "B.Fab")
			(hide yes)
			(effects
				(font
					(size 1.016 1.016)
					(thickness 0.1524)
				)
				(justify mirror)
			)
		)
		(property "Device Type" "C603H40"
			(at 0 -4.3434 180)
			(unlocked yes)
			(layer "B.Fab")
			(hide yes)
			(effects
				(font
					(size 1.016 1.016)
					(thickness 0.1524)
				)
				(justify mirror)
			)
		)
		(duplicate_pad_numbers_are_jumpers no)
		(fp_line
			(start -0.508 0)
			(end 0.508 0)
			(stroke
				(width 0.2032)
				(type default)
			)
			(layer "B.SilkS")
		)
		(fp_rect
			(start 0.5842 1.3335)
			(end -0.5842 -1.3335)
			(stroke
				(width 0)
				(type default)
			)
			(fill no)
			(layer "B.CrtYd")
		)
		(fp_rect
			(start 0.5842 1.3335)
			(end -0.5842 -1.3335)
			(stroke
				(width 0)
				(type default)
			)
			(fill no)
			(layer "B.Fab")
		)
		(pad "1" smd custom
			(at 0 -0.762)
			(size 0.2159 0.2159)
			(layers "B.Cu" "B.Mask" "B.Paste")
			(net "GND")
			(options
				(clearance outline)
				(anchor circle)
			)
			(primitives
				(gr_poly
					(pts
						(arc
							(start -0.3302 0.4318)
							(mid -0.402042 0.402042)
							(end -0.4318 0.3302)
						)
						(arc
							(start -0.4318 -0.3302)
							(mid -0.402042 -0.402042)
							(end -0.3302 -0.4318)
						)
						(arc
							(start 0.3302 -0.4318)
							(mid 0.402042 -0.402042)
							(end 0.4318 -0.3302)
						)
						(arc
							(start 0.4318 0.3302)
							(mid 0.402042 0.402042)
							(end 0.3302 0.4318)
						)
					)
					(width 0)
					(fill yes)
				)
			)
		)
		(pad "2" smd custom
			(at 0 0.762)
			(size 0.2159 0.2159)
			(layers "B.Cu" "B.Mask" "B.Paste")
			(net "P1V15_STBY")
			(options
				(clearance outline)
				(anchor circle)
			)
			(primitives
				(gr_poly
					(pts
						(arc
							(start -0.3302 0.4318)
							(mid -0.402042 0.402042)
							(end -0.4318 0.3302)
						)
						(arc
							(start -0.4318 -0.3302)
							(mid -0.402042 -0.402042)
							(end -0.3302 -0.4318)
						)
						(arc
							(start 0.3302 -0.4318)
							(mid 0.402042 -0.402042)
							(end 0.4318 -0.3302)
						)
						(arc
							(start 0.4318 0.3302)
							(mid 0.402042 0.402042)
							(end 0.3302 0.4318)
						)
					)
					(width 0)
					(fill yes)
				)
			)
		)
	)
	(footprint ""
		(layer "B.Cu")
		(at 189.1284 -124.405136 180)
		(property "Reference" "R561"
			(at 0 0 0)
			(layer "B.SilkS")
			(hide yes)
			(effects
				(font
					(size 1.27 1.27)
				)
				(justify mirror)
			)
		)
		(property "Value" "10KR2F-2-GP"
			(at -0.064008 -3.993896 180)
			(unlocked yes)
			(layer "B.Fab")
			(hide yes)
			(effects
				(font
					(size 1.016 1.016)
					(thickness 0.1524)
				)
				(justify mirror)
			)
		)
		(property "Device Type" "R402H16"
			(at -0.064008 -5.517896 180)
			(unlocked yes)
			(layer "B.Fab")
			(hide yes)
			(effects
				(font
					(size 1.016 1.016)
					(thickness 0.1524)
				)
				(justify mirror)
			)
		)
		(duplicate_pad_numbers_are_jumpers no)
		(fp_line
			(start 0.508 -0.9398)
			(end 0.508 0.9398)
			(stroke
				(width 0.1524)
				(type default)
			)
			(layer "B.SilkS")
		)
		(fp_line
			(start -0.508 -0.9398)
			(end 0.508 -0.9398)
			(stroke
				(width 0.1524)
				(type default)
			)
			(layer "B.SilkS")
		)
		(fp_rect
			(start 0.508 0.9398)
			(end -0.508 -0.9398)
			(stroke
				(width 0)
				(type default)
			)
			(fill no)
			(layer "B.CrtYd")
		)
		(fp_rect
			(start 0.508 0.9398)
			(end -0.508 -0.9398)
			(stroke
				(width 0)
				(type default)
			)
			(fill no)
			(layer "B.Fab")
		)
		(pad "1" smd custom
			(at 0 -0.4445)
			(size 0.1397 0.1397)
			(layers "B.Cu" "B.Mask" "B.Paste")
			(net "AGND_P0V975")
			(options
				(clearance outline)
				(anchor circle)
			)
			(primitives
				(gr_poly
					(pts
						(arc
							(start -0.1778 0.2794)
							(mid -0.249642 0.249642)
							(end -0.2794 0.1778)
						)
						(arc
							(start -0.2794 -0.1778)
							(mid -0.249642 -0.249642)
							(end -0.1778 -0.2794)
						)
						(arc
							(start 0.1778 -0.2794)
							(mid 0.249642 -0.249642)
							(end 0.2794 -0.1778)
						)
						(arc
							(start 0.2794 0.1778)
							(mid 0.249642 0.249642)
							(end 0.1778 0.2794)
						)
					)
					(width 0)
					(fill yes)
				)
			)
		)
		(pad "2" smd custom
			(at 0 0.4445)
			(size 0.1397 0.1397)
			(layers "B.Cu" "B.Mask" "B.Paste")
			(net "VT235_BIAS")
			(options
				(clearance outline)
				(anchor circle)
			)
			(primitives
				(gr_poly
					(pts
						(arc
							(start -0.1778 0.2794)
							(mid -0.249642 0.249642)
							(end -0.2794 0.1778)
						)
						(arc
							(start -0.2794 -0.1778)
							(mid -0.249642 -0.249642)
							(end -0.1778 -0.2794)
						)
						(arc
							(start 0.1778 -0.2794)
							(mid 0.249642 -0.249642)
							(end 0.2794 -0.1778)
						)
						(arc
							(start 0.2794 0.1778)
							(mid 0.249642 0.249642)
							(end 0.1778 0.2794)
						)
					)
					(width 0)
					(fill yes)
				)
			)
		)
	)
	(footprint ""
		(layer "B.Cu")
		(at 200.4314 -68.326 90)
		(property "Reference" "C354"
			(at 0 0 90)
			(layer "B.SilkS")
			(hide yes)
			(effects
				(font
					(size 1.27 1.27)
				)
				(justify mirror)
			)
		)
		(property "Value" "SCD1U6D3V1KX-GP"
			(at 2.8321 -1.7399 90)
			(unlocked yes)
			(layer "B.Fab")
			(hide yes)
			(effects
				(font
					(size 1.016 1.016)
					(thickness 0.1524)
				)
				(justify mirror)
			)
		)
		(property "Device Type" "C0201H13"
			(at 2.8321 -3.2639 90)
			(unlocked yes)
			(layer "B.Fab")
			(hide yes)
			(effects
				(font
					(size 1.016 1.016)
					(thickness 0.1524)
				)
				(justify mirror)
			)
		)
		(duplicate_pad_numbers_are_jumpers no)
		(fp_rect
			(start 0.2794 0.6477)
			(end -0.2794 -0.6477)
			(stroke
				(width 0)
				(type default)
			)
			(fill no)
			(layer "B.CrtYd")
		)
		(fp_rect
			(start 0.2794 0.6477)
			(end -0.2794 -0.6477)
			(stroke
				(width 0)
				(type default)
			)
			(fill no)
			(layer "B.Fab")
		)
		(pad "1" smd custom
			(at 0 -0.2794 270)
			(size 0.0762 0.0762)
			(layers "B.Cu" "B.Mask" "B.Paste")
			(net "SAS0_VDDH")
			(options
				(clearance outline)
				(anchor circle)
			)
			(primitives
				(gr_poly
					(pts
						(arc
							(start 0.1524 0.127)
							(mid 0.137521 0.162921)
							(end 0.1016 0.1778)
						)
						(arc
							(start -0.1016 0.1778)
							(mid -0.137521 0.162921)
							(end -0.1524 0.127)
						)
						(arc
							(start -0.1524 -0.127)
							(mid -0.137521 -0.162921)
							(end -0.1016 -0.1778)
						)
						(arc
							(start 0.1016 -0.1778)
							(mid 0.137521 -0.162921)
							(end 0.1524 -0.127)
						)
					)
					(width 0)
					(fill yes)
				)
			)
		)
		(pad "2" smd custom
			(at 0 0.2794 270)
			(size 0.0762 0.0762)
			(layers "B.Cu" "B.Mask" "B.Paste")
			(net "GND")
			(options
				(clearance outline)
				(anchor circle)
			)
			(primitives
				(gr_poly
					(pts
						(arc
							(start 0.1524 0.127)
							(mid 0.137521 0.162921)
							(end 0.1016 0.1778)
						)
						(arc
							(start -0.1016 0.1778)
							(mid -0.137521 0.162921)
							(end -0.1524 0.127)
						)
						(arc
							(start -0.1524 -0.127)
							(mid -0.137521 -0.162921)
							(end -0.1016 -0.1778)
						)
						(arc
							(start 0.1016 -0.1778)
							(mid 0.137521 -0.162921)
							(end 0.1524 -0.127)
						)
					)
					(width 0)
					(fill yes)
				)
			)
		)
	)
	(footprint ""
		(layer "B.Cu")
		(at 38.117018 -155.560522 180)
		(property "Reference" "R316"
			(at 0 0 0)
			(layer "B.SilkS")
			(hide yes)
			(effects
				(font
					(size 1.27 1.27)
				)
				(justify mirror)
			)
		)
		(property "Value" "0R2J-2-GP"
			(at -0.064262 -3.993642 180)
			(unlocked yes)
			(layer "B.Fab")
			(hide yes)
			(effects
				(font
					(size 1.016 1.016)
					(thickness 0.1524)
				)
				(justify mirror)
			)
		)
		(property "Device Type" "R402H16"
			(at -0.064262 -5.517896 180)
			(unlocked yes)
			(layer "B.Fab")
			(hide yes)
			(effects
				(font
					(size 1.016 1.016)
					(thickness 0.1524)
				)
				(justify mirror)
			)
		)
		(duplicate_pad_numbers_are_jumpers no)
		(fp_line
			(start 0.508 -0.9398)
			(end 0.508 0.9398)
			(stroke
				(width 0.1524)
				(type default)
			)
			(layer "B.SilkS")
		)
		(fp_line
			(start -0.508 -0.9398)
			(end 0.508 -0.9398)
			(stroke
				(width 0.1524)
				(type default)
			)
			(layer "B.SilkS")
		)
		(fp_rect
			(start 0.508 0.9398)
			(end -0.508 -0.9398)
			(stroke
				(width 0)
				(type default)
			)
			(fill no)
			(layer "B.CrtYd")
		)
		(fp_rect
			(start 0.508 0.9398)
			(end -0.508 -0.9398)
			(stroke
				(width 0)
				(type default)
			)
			(fill no)
			(layer "B.Fab")
		)
		(pad "1" smd custom
			(at 0 -0.4445)
			(size 0.1397 0.1397)
			(layers "B.Cu" "B.Mask" "B.Paste")
			(net "BMC_RMT_HB")
			(options
				(clearance outline)
				(anchor circle)
			)
			(primitives
				(gr_poly
					(pts
						(arc
							(start -0.1778 0.2794)
							(mid -0.249642 0.249642)
							(end -0.2794 0.1778)
						)
						(arc
							(start -0.2794 -0.1778)
							(mid -0.249642 -0.249642)
							(end -0.1778 -0.2794)
						)
						(arc
							(start 0.1778 -0.2794)
							(mid 0.249642 -0.249642)
							(end 0.2794 -0.1778)
						)
						(arc
							(start 0.2794 0.1778)
							(mid 0.249642 0.249642)
							(end 0.1778 0.2794)
						)
					)
					(width 0)
					(fill yes)
				)
			)
		)
		(pad "2" smd custom
			(at 0 0.4445)
			(size 0.1397 0.1397)
			(layers "B.Cu" "B.Mask" "B.Paste")
			(net "BMC_RMT_HEARTBEAT")
			(options
				(clearance outline)
				(anchor circle)
			)
			(primitives
				(gr_poly
					(pts
						(arc
							(start -0.1778 0.2794)
							(mid -0.249642 0.249642)
							(end -0.2794 0.1778)
						)
						(arc
							(start -0.2794 -0.1778)
							(mid -0.249642 -0.249642)
							(end -0.1778 -0.2794)
						)
						(arc
							(start 0.1778 -0.2794)
							(mid 0.249642 -0.249642)
							(end 0.2794 -0.1778)
						)
						(arc
							(start 0.2794 0.1778)
							(mid 0.249642 0.249642)
							(end 0.1778 0.2794)
						)
					)
					(width 0)
					(fill yes)
				)
			)
		)
	)
	(footprint ""
		(layer "B.Cu")
		(at 202.463146 -61.35243)
		(property "Reference" "C454"
			(at 0 0 0)
			(layer "B.SilkS")
			(hide yes)
			(effects
				(font
					(size 1.27 1.27)
				)
				(justify mirror)
			)
		)
		(property "Value" "SCD1U16V2KX-3GP"
			(at -1.1811 -2.7051 0)
			(unlocked yes)
			(layer "B.Fab")
			(hide yes)
			(effects
				(font
					(size 1.016 1.016)
					(thickness 0.1524)
				)
				(justify mirror)
			)
		)
		(property "Device Type" "C402H22"
			(at -1.1811 -4.2291 0)
			(unlocked yes)
			(layer "B.Fab")
			(hide yes)
			(effects
				(font
					(size 1.016 1.016)
					(thickness 0.1524)
				)
				(justify mirror)
			)
		)
		(duplicate_pad_numbers_are_jumpers no)
		(fp_rect
			(start 0.4318 0.9525)
			(end -0.4318 -0.9525)
			(stroke
				(width 0)
				(type default)
			)
			(fill no)
			(layer "B.CrtYd")
		)
		(fp_rect
			(start 0.4318 0.9525)
			(end -0.4318 -0.9525)
			(stroke
				(width 0)
				(type default)
			)
			(fill no)
			(layer "B.Fab")
		)
		(pad "1" smd custom
			(at 0 -0.4445 180)
			(size 0.1524 0.1524)
			(layers "B.Cu" "B.Mask" "B.Paste")
			(net "P1V8")
			(options
				(clearance outline)
				(anchor circle)
			)
			(primitives
				(gr_poly
					(pts
						(arc
							(start 0.3048 0.2032)
							(mid 0.275042 0.275042)
							(end 0.2032 0.3048)
						)
						(arc
							(start -0.2032 0.3048)
							(mid -0.275042 0.275042)
							(end -0.3048 0.2032)
						)
						(arc
							(start -0.3048 -0.2032)
							(mid -0.275042 -0.275042)
							(end -0.2032 -0.3048)
						)
						(arc
							(start 0.2032 -0.3048)
							(mid 0.275042 -0.275042)
							(end 0.3048 -0.2032)
						)
					)
					(width 0)
					(fill yes)
				)
			)
		)
		(pad "2" smd custom
			(at 0 0.4445 180)
			(size 0.1524 0.1524)
			(layers "B.Cu" "B.Mask" "B.Paste")
			(net "GND")
			(options
				(clearance outline)
				(anchor circle)
			)
			(primitives
				(gr_poly
					(pts
						(arc
							(start 0.3048 0.2032)
							(mid 0.275042 0.275042)
							(end 0.2032 0.3048)
						)
						(arc
							(start -0.2032 0.3048)
							(mid -0.275042 0.275042)
							(end -0.3048 0.2032)
						)
						(arc
							(start -0.3048 -0.2032)
							(mid -0.275042 -0.275042)
							(end -0.2032 -0.3048)
						)
						(arc
							(start 0.2032 -0.3048)
							(mid 0.275042 -0.275042)
							(end 0.3048 -0.2032)
						)
					)
					(width 0)
					(fill yes)
				)
			)
		)
	)
	(footprint ""
		(layer "B.Cu")
		(at 94.0054 -143.087852 -90)
		(property "Reference" "Q26"
			(at 0 0 90)
			(layer "B.SilkS")
			(hide yes)
			(effects
				(font
					(size 1.27 1.27)
				)
				(justify mirror)
			)
		)
		(property "Value" "2N7002K-1-GP"
			(at -0.127 -8.9662 270)
			(unlocked yes)
			(layer "B.Fab")
			(hide yes)
			(effects
				(font
					(size 1.016 1.016)
					(thickness 0.1524)
				)
				(justify mirror)
			)
		)
		(property "Device Type" "SOT23DGS2D4H44"
			(at -0.127 -10.4902 270)
			(unlocked yes)
			(layer "B.Fab")
			(hide yes)
			(effects
				(font
					(size 1.016 1.016)
					(thickness 0.1524)
				)
				(justify mirror)
			)
		)
		(duplicate_pad_numbers_are_jumpers no)
		(fp_line
			(start -1.651 1.778)
			(end -1.651 -1.778)
			(stroke
				(width 0.1524)
				(type default)
			)
			(layer "B.SilkS")
		)
		(fp_line
			(start 1.651 1.778)
			(end -1.651 1.778)
			(stroke
				(width 0.1524)
				(type default)
			)
			(layer "B.SilkS")
		)
		(fp_line
			(start -1.651 -1.778)
			(end 1.651 -1.778)
			(stroke
				(width 0.1524)
				(type default)
			)
			(layer "B.SilkS")
		)
		(fp_line
			(start 1.651 -1.778)
			(end 1.651 1.778)
			(stroke
				(width 0.1524)
				(type default)
			)
			(layer "B.SilkS")
		)
		(fp_poly
			(pts
				(xy 1.778 1.8796) (xy 1.778 -1.8796) (xy -1.778 -1.8796) (xy -1.778 1.8796)
			)
			(stroke
				(width 0)
				(type default)
			)
			(fill no)
			(layer "B.CrtYd")
		)
		(fp_poly
			(pts
				(xy 1.778 1.8796) (xy 1.778 -1.8796) (xy -1.778 -1.8796) (xy -1.778 1.8796)
			)
			(stroke
				(width 0)
				(type default)
			)
			(fill no)
			(layer "B.Fab")
		)
		(pad "D" smd custom
			(at 0 -0.9525 90)
			(size 0.1905 0.1905)
			(layers "B.Cu" "B.Mask" "B.Paste")
			(net "DB_PRSNT_BMC_N")
			(options
				(clearance outline)
				(anchor circle)
			)
			(primitives
				(gr_poly
					(pts
						(arc
							(start -0.1778 -0.5715)
							(mid -0.321484 -0.511984)
							(end -0.381 -0.3683)
						)
						(arc
							(start -0.381 0.3683)
							(mid -0.321484 0.511984)
							(end -0.1778 0.5715)
						)
						(arc
							(start 0.1778 0.5715)
							(mid 0.321484 0.511984)
							(end 0.381 0.3683)
						)
						(arc
							(start 0.381 -0.3683)
							(mid 0.321484 -0.511984)
							(end 0.1778 -0.5715)
						)
					)
					(width 0)
					(fill yes)
				)
			)
		)
		(pad "G" smd custom
			(at 0.98425 0.9525 90)
			(size 0.1905 0.1905)
			(layers "B.Cu" "B.Mask" "B.Paste")
			(net "DEBUG_CARD_PRSNT")
			(options
				(clearance outline)
				(anchor circle)
			)
			(primitives
				(gr_poly
					(pts
						(arc
							(start -0.1778 -0.5715)
							(mid -0.321484 -0.511984)
							(end -0.381 -0.3683)
						)
						(arc
							(start -0.381 0.3683)
							(mid -0.321484 0.511984)
							(end -0.1778 0.5715)
						)
						(arc
							(start 0.1778 0.5715)
							(mid 0.321484 0.511984)
							(end 0.381 0.3683)
						)
						(arc
							(start 0.381 -0.3683)
							(mid 0.321484 -0.511984)
							(end 0.1778 -0.5715)
						)
					)
					(width 0)
					(fill yes)
				)
			)
		)
		(pad "S" smd custom
			(at -0.98425 0.9525 90)
			(size 0.1905 0.1905)
			(layers "B.Cu" "B.Mask" "B.Paste")
			(net "GND")
			(options
				(clearance outline)
				(anchor circle)
			)
			(primitives
				(gr_poly
					(pts
						(arc
							(start -0.1778 -0.5715)
							(mid -0.321484 -0.511984)
							(end -0.381 -0.3683)
						)
						(arc
							(start -0.381 0.3683)
							(mid -0.321484 0.511984)
							(end -0.1778 0.5715)
						)
						(arc
							(start 0.1778 0.5715)
							(mid 0.321484 0.511984)
							(end 0.381 0.3683)
						)
						(arc
							(start 0.381 -0.3683)
							(mid 0.321484 -0.511984)
							(end 0.1778 -0.5715)
						)
					)
					(width 0)
					(fill yes)
				)
			)
		)
	)
)
